(kicad_pcb
	(version 20260206)
	(generator "pcbnew")
	(generator_version "10.0")
	(general
		(thickness 1.6)
		(legacy_teardrops no)
	)
	(paper "A4")
	(title_block
		(title "v1-chassis-manager — T6M_CM_d_v01_1031_1645.brd")
		(comment 1 "Open CloudServer (Microsoft) / footprints 67-76 of 2512")
	)
	(layers
		(0 "F.Cu" signal "TOP")
		(4 "In1.Cu" signal "GND1")
		(6 "In2.Cu" signal "IN1")
		(8 "In3.Cu" signal "VCC1")
		(10 "In4.Cu" signal "VCC2")
		(12 "In5.Cu" signal "GND2")
		(14 "In6.Cu" signal "IN2")
		(16 "In7.Cu" signal "IN3")
		(18 "In8.Cu" signal "GND3")
		(2 "B.Cu" signal "BOTTOM")
		(9 "F.Adhes" user "F.Adhesive")
		(11 "B.Adhes" user "B.Adhesive")
		(13 "F.Paste" user "Package Geometry/Pastemask Top")
		(15 "B.Paste" user "Package Geometry/Pastemask Bottom")
		(5 "F.SilkS" user "Ref Des/Silkscreen Top")
		(7 "B.SilkS" user "Ref Des/Silkscreen Bottom")
		(1 "F.Mask" user "Board Geometry/Soldermask Top")
		(3 "B.Mask" user "Board Geometry/Soldermask Bottom")
		(17 "Dwgs.User" user "User.Drawings")
		(19 "Cmts.User" user "User.Comments")
		(21 "Eco1.User" user "User.Eco1")
		(23 "Eco2.User" user "User.Eco2")
		(25 "Edge.Cuts" user "Board Geometry/Outline")
		(27 "Margin" user)
		(31 "F.CrtYd" user "Package Geometry/Place Bound Top")
		(29 "B.CrtYd" user "Package Geometry/Place Bound Bottom")
		(35 "F.Fab" user "Ref Des/Assembly Top")
		(33 "B.Fab" user "Ref Des/Assembly Bottom")
	)
	(footprint ""
		(layer "F.Cu")
		(at 117.435376 -128.387348 -90)
		(property "Reference" "PR49"
			(at 1.917192 -2.019554 90)
			(unlocked yes)
			(layer "F.SilkS")
			(effects
				(font
					(size 0.7874 0.5842)
					(thickness 0.1524)
				)
				(justify left)
			)
		)
		(property "Value" ""
			(at 0 0 270)
			(layer "F.Fab")
			(effects
				(font
					(size 1.27 1.27)
				)
			)
		)
		(duplicate_pad_numbers_are_jumpers no)
		(fp_line
			(start -2.2098 0.9398)
			(end -2.2098 -0.9398)
			(stroke
				(width 0.1524)
				(type default)
			)
			(layer "F.SilkS")
		)
		(fp_line
			(start 2.2098 0.9398)
			(end -2.2098 0.9398)
			(stroke
				(width 0.1524)
				(type default)
			)
			(layer "F.SilkS")
		)
		(fp_line
			(start -2.2098 -0.9398)
			(end 2.2098 -0.9398)
			(stroke
				(width 0.1524)
				(type default)
			)
			(layer "F.SilkS")
		)
		(fp_line
			(start 2.2098 -0.9398)
			(end 2.2098 0.9398)
			(stroke
				(width 0.1524)
				(type default)
			)
			(layer "F.SilkS")
		)
		(fp_poly
			(pts
				(xy 2.0574 0.8382) (xy 2.0574 -0.8382) (xy 2.0574 -0.9398) (xy -2.0574 -0.9398) (xy -2.0574 -0.8382)
				(xy -2.0574 0.8382) (xy -2.0574 0.9398) (xy 2.0574 0.9398)
			)
			(stroke
				(width 0)
				(type default)
			)
			(fill no)
			(layer "F.CrtYd")
		)
		(pad "1" smd rect
			(at 1.4732 0 270)
			(size 1.1684 1.5748)
			(layers "F.Cu" "F.Mask" "F.Paste")
			(net "SW_VR_PVCCP_NODE1_VIN_FLT")
		)
		(pad "2" smd rect
			(at -1.4732 0 270)
			(size 1.1684 1.5748)
			(layers "F.Cu" "F.Mask" "F.Paste")
			(net "P12V_AUX")
		)
	)
	(footprint ""
		(layer "F.Cu")
		(at 184.2516 -188.4172 -90)
		(property "Reference" "R1296"
			(at -1.1176 -0.28067 90)
			(unlocked yes)
			(layer "F.SilkS")
			(effects
				(font
					(size 0.7874 0.5842)
					(thickness 0.1524)
				)
				(justify left)
			)
		)
		(property "Value" ""
			(at 0 0 270)
			(layer "F.Fab")
			(effects
				(font
					(size 1.27 1.27)
				)
			)
		)
		(duplicate_pad_numbers_are_jumpers no)
		(fp_line
			(start -0.7874 0.4064)
			(end -0.7874 -0.4064)
			(stroke
				(width 0.1524)
				(type default)
			)
			(layer "F.SilkS")
		)
		(fp_line
			(start 0.7874 0.4064)
			(end -0.7874 0.4064)
			(stroke
				(width 0.1524)
				(type default)
			)
			(layer "F.SilkS")
		)
		(fp_line
			(start -0.7874 -0.4064)
			(end 0.7874 -0.4064)
			(stroke
				(width 0.1524)
				(type default)
			)
			(layer "F.SilkS")
		)
		(fp_line
			(start 0.7874 -0.4064)
			(end 0.7874 0.4064)
			(stroke
				(width 0.1524)
				(type default)
			)
			(layer "F.SilkS")
		)
		(fp_poly
			(pts
				(xy -0.508 0.2794) (xy -0.508 0.2286) (xy -0.635 0.2286) (xy -0.635 -0.254) (xy -0.5334 -0.254)
				(xy -0.5334 -0.2794) (xy 0.5334 -0.2794) (xy 0.5334 -0.254) (xy 0.635 -0.254) (xy 0.635 0.254) (xy 0.5334 0.254)
				(xy 0.5334 0.2794)
			)
			(stroke
				(width 0)
				(type default)
			)
			(fill no)
			(layer "F.CrtYd")
		)
		(pad "1" smd rect
			(at 0.40005 0 270)
			(size 0.4572 0.508)
			(layers "F.Cu" "F.Mask" "F.Paste")
			(net "POWER_SW1_PWR_CTR_12V")
		)
		(pad "2" smd rect
			(at -0.40005 0 270)
			(size 0.4572 0.508)
			(layers "F.Cu" "F.Mask" "F.Paste")
			(net "POWER_SW1_PWR_CTR_12V_R")
		)
	)
	(footprint ""
		(layer "F.Cu")
		(at 107.134152 -129.483358 90)
		(property "Reference" "PC88"
			(at -3.252978 -7.426706 90)
			(unlocked yes)
			(layer "F.SilkS")
			(effects
				(font
					(size 0.7874 0.5842)
					(thickness 0.1524)
				)
			)
		)
		(property "Value" ""
			(at 0 0 90)
			(layer "F.Fab")
			(effects
				(font
					(size 1.27 1.27)
				)
			)
		)
		(duplicate_pad_numbers_are_jumpers no)
		(fp_line
			(start 1.2954 -0.5842)
			(end 1.2954 0.5842)
			(stroke
				(width 0.1524)
				(type default)
			)
			(layer "F.SilkS")
		)
		(fp_line
			(start 0 -0.5842)
			(end 0 0.5842)
			(stroke
				(width 0.1524)
				(type default)
			)
			(layer "F.SilkS")
		)
		(fp_line
			(start -1.2954 -0.5842)
			(end 1.2954 -0.5842)
			(stroke
				(width 0.1524)
				(type default)
			)
			(layer "F.SilkS")
		)
		(fp_line
			(start 1.2954 0.5842)
			(end -1.2954 0.5842)
			(stroke
				(width 0.1524)
				(type default)
			)
			(layer "F.SilkS")
		)
		(fp_line
			(start -1.2954 0.5842)
			(end -1.2954 -0.5842)
			(stroke
				(width 0.1524)
				(type default)
			)
			(layer "F.SilkS")
		)
		(fp_poly
			(pts
				(xy 0.8636 -0.4572) (xy 0.8636 -0.3556) (xy 1.143 -0.3556) (xy 1.143 0.3556) (xy 0.8636 0.3556)
				(xy 0.8636 0.4572) (xy -0.8636 0.4572) (xy -0.8636 0.3556) (xy -1.143 0.3556) (xy -1.143 -0.3556)
				(xy -0.8636 -0.3556) (xy -0.8636 -0.4572)
			)
			(stroke
				(width 0)
				(type default)
			)
			(fill no)
			(layer "F.CrtYd")
		)
		(fp_line
			(start 0.884936 -0.504952)
			(end 0.884936 0.504952)
			(stroke
				(width 0.1)
				(type default)
			)
			(layer "F.Fab")
		)
		(fp_line
			(start -0.884936 -0.504952)
			(end 0.884936 -0.504952)
			(stroke
				(width 0.1)
				(type default)
			)
			(layer "F.Fab")
		)
		(fp_line
			(start 0.884936 0.504952)
			(end -0.884936 0.504952)
			(stroke
				(width 0.1)
				(type default)
			)
			(layer "F.Fab")
		)
		(fp_line
			(start -0.884936 0.504952)
			(end -0.884936 -0.504952)
			(stroke
				(width 0.1)
				(type default)
			)
			(layer "F.Fab")
		)
		(pad "1" smd rect
			(at 0.7366 0 180)
			(size 0.7112 0.8128)
			(layers "F.Cu" "F.Mask" "F.Paste")
			(net "VR_PVCCP_NODE1_PVCC")
		)
		(pad "2" smd rect
			(at -0.7366 0 180)
			(size 0.7112 0.8128)
			(layers "F.Cu" "F.Mask" "F.Paste")
			(net "GND")
		)
	)
	(footprint ""
		(layer "F.Cu")
		(at 28.85948 -101.538786 90)
		(property "Reference" "C817"
			(at -1.358138 1.33858 0)
			(unlocked yes)
			(layer "F.SilkS")
			(effects
				(font
					(size 0.7874 0.5842)
					(thickness 0.1524)
				)
				(justify left)
			)
		)
		(property "Value" ""
			(at 0 0 90)
			(layer "F.Fab")
			(effects
				(font
					(size 1.27 1.27)
				)
			)
		)
		(duplicate_pad_numbers_are_jumpers no)
		(fp_line
			(start 0.7874 -0.4064)
			(end 0.7874 0.4064)
			(stroke
				(width 0.1524)
				(type default)
			)
			(layer "F.SilkS")
		)
		(fp_line
			(start -0.7874 -0.4064)
			(end 0.7874 -0.4064)
			(stroke
				(width 0.1524)
				(type default)
			)
			(layer "F.SilkS")
		)
		(fp_line
			(start 0 0.381)
			(end 0 -0.381)
			(stroke
				(width 0.1524)
				(type default)
			)
			(layer "F.SilkS")
		)
		(fp_line
			(start 0.7874 0.4064)
			(end -0.7874 0.4064)
			(stroke
				(width 0.1524)
				(type default)
			)
			(layer "F.SilkS")
		)
		(fp_line
			(start -0.7874 0.4064)
			(end -0.7874 -0.4064)
			(stroke
				(width 0.1524)
				(type default)
			)
			(layer "F.SilkS")
		)
		(fp_poly
			(pts
				(xy -0.5334 0.254) (xy -0.635 0.254) (xy -0.635 0.2286) (xy -0.635 -0.254) (xy -0.5334 -0.254) (xy -0.5334 -0.2794)
				(xy 0.5334 -0.2794) (xy 0.5334 -0.254) (xy 0.635 -0.254) (xy 0.635 0.254) (xy 0.5334 0.254) (xy 0.5334 0.2794)
				(xy -0.508 0.2794) (xy -0.5334 0.2794)
			)
			(stroke
				(width 0)
				(type default)
			)
			(fill no)
			(layer "F.CrtYd")
		)
		(pad "1" smd rect
			(at 0.40005 0 90)
			(size 0.4572 0.508)
			(layers "F.Cu" "F.Mask" "F.Paste")
			(net "P5V_STB_NODE1")
		)
		(pad "2" smd rect
			(at -0.40005 0 90)
			(size 0.4572 0.508)
			(layers "F.Cu" "F.Mask" "F.Paste")
			(net "GND")
		)
	)
	(footprint ""
		(layer "F.Cu")
		(at 61.470286 -118.910862 90)
		(property "Reference" "R322"
			(at -5.140706 0.65024 90)
			(unlocked yes)
			(layer "F.SilkS")
			(effects
				(font
					(size 0.7874 0.5842)
					(thickness 0.1524)
				)
				(justify left)
			)
		)
		(property "Value" ""
			(at 0 0 90)
			(layer "F.Fab")
			(effects
				(font
					(size 1.27 1.27)
				)
			)
		)
		(duplicate_pad_numbers_are_jumpers no)
		(fp_line
			(start 0.7874 -0.4064)
			(end 0.7874 0.4064)
			(stroke
				(width 0.1524)
				(type default)
			)
			(layer "F.SilkS")
		)
		(fp_line
			(start -0.7874 -0.4064)
			(end 0.7874 -0.4064)
			(stroke
				(width 0.1524)
				(type default)
			)
			(layer "F.SilkS")
		)
		(fp_line
			(start 0.7874 0.4064)
			(end -0.7874 0.4064)
			(stroke
				(width 0.1524)
				(type default)
			)
			(layer "F.SilkS")
		)
		(fp_line
			(start -0.7874 0.4064)
			(end -0.7874 -0.4064)
			(stroke
				(width 0.1524)
				(type default)
			)
			(layer "F.SilkS")
		)
		(fp_poly
			(pts
				(xy -0.508 0.2794) (xy -0.508 0.2286) (xy -0.635 0.2286) (xy -0.635 -0.254) (xy -0.5334 -0.254)
				(xy -0.5334 -0.2794) (xy 0.5334 -0.2794) (xy 0.5334 -0.254) (xy 0.635 -0.254) (xy 0.635 0.254) (xy 0.5334 0.254)
				(xy 0.5334 0.2794)
			)
			(stroke
				(width 0)
				(type default)
			)
			(fill no)
			(layer "F.CrtYd")
		)
		(pad "1" smd rect
			(at 0.40005 0 90)
			(size 0.4572 0.508)
			(layers "F.Cu" "F.Mask" "F.Paste")
			(net "P3V3_NODE1")
		)
		(pad "2" smd rect
			(at -0.40005 0 90)
			(size 0.4572 0.508)
			(layers "F.Cu" "F.Mask" "F.Paste")
			(net "BMC_ROMA6")
		)
	)
	(footprint ""
		(layer "F.Cu")
		(at 139.000992 -25.802844 -90)
		(property "Reference" "C493"
			(at 10.72261 -4.28625 90)
			(unlocked yes)
			(layer "F.SilkS")
			(effects
				(font
					(size 0.7874 0.5842)
					(thickness 0.1524)
				)
				(justify left)
			)
		)
		(property "Value" ""
			(at 0 0 270)
			(layer "F.Fab")
			(effects
				(font
					(size 1.27 1.27)
				)
			)
		)
		(duplicate_pad_numbers_are_jumpers no)
		(fp_line
			(start -0.7874 0.4064)
			(end -0.7874 -0.4064)
			(stroke
				(width 0.1524)
				(type default)
			)
			(layer "F.SilkS")
		)
		(fp_line
			(start 0.7874 0.4064)
			(end -0.7874 0.4064)
			(stroke
				(width 0.1524)
				(type default)
			)
			(layer "F.SilkS")
		)
		(fp_line
			(start 0 0.381)
			(end 0 -0.381)
			(stroke
				(width 0.1524)
				(type default)
			)
			(layer "F.SilkS")
		)
		(fp_line
			(start -0.7874 -0.4064)
			(end 0.7874 -0.4064)
			(stroke
				(width 0.1524)
				(type default)
			)
			(layer "F.SilkS")
		)
		(fp_line
			(start 0.7874 -0.4064)
			(end 0.7874 0.4064)
			(stroke
				(width 0.1524)
				(type default)
			)
			(layer "F.SilkS")
		)
		(fp_poly
			(pts
				(xy -0.5334 0.254) (xy -0.635 0.254) (xy -0.635 0.2286) (xy -0.635 -0.254) (xy -0.5334 -0.254) (xy -0.5334 -0.2794)
				(xy 0.5334 -0.2794) (xy 0.5334 -0.254) (xy 0.635 -0.254) (xy 0.635 0.254) (xy 0.5334 0.254) (xy 0.5334 0.2794)
				(xy -0.508 0.2794) (xy -0.5334 0.2794)
			)
			(stroke
				(width 0)
				(type default)
			)
			(fill no)
			(layer "F.CrtYd")
		)
		(pad "1" smd rect
			(at 0.40005 0 270)
			(size 0.4572 0.508)
			(layers "F.Cu" "F.Mask" "F.Paste")
			(net "P5V_NODE1")
		)
		(pad "2" smd rect
			(at -0.40005 0 270)
			(size 0.4572 0.508)
			(layers "F.Cu" "F.Mask" "F.Paste")
			(net "GND")
		)
	)
	(footprint ""
		(layer "F.Cu")
		(at 90.80754 -175.418496 180)
		(property "Reference" "C909"
			(at -85.979 -76.25969 0)
			(unlocked yes)
			(layer "F.SilkS")
			(effects
				(font
					(size 0.7874 0.5842)
					(thickness 0.1524)
				)
				(justify left)
			)
		)
		(property "Value" ""
			(at 0 0 180)
			(layer "F.Fab")
			(effects
				(font
					(size 1.27 1.27)
				)
			)
		)
		(duplicate_pad_numbers_are_jumpers no)
		(fp_line
			(start 0.7874 0.4064)
			(end -0.7874 0.4064)
			(stroke
				(width 0.1524)
				(type default)
			)
			(layer "F.SilkS")
		)
		(fp_line
			(start 0.7874 -0.4064)
			(end 0.7874 0.4064)
			(stroke
				(width 0.1524)
				(type default)
			)
			(layer "F.SilkS")
		)
		(fp_line
			(start 0 0.381)
			(end 0 -0.381)
			(stroke
				(width 0.1524)
				(type default)
			)
			(layer "F.SilkS")
		)
		(fp_line
			(start -0.7874 0.4064)
			(end -0.7874 -0.4064)
			(stroke
				(width 0.1524)
				(type default)
			)
			(layer "F.SilkS")
		)
		(fp_line
			(start -0.7874 -0.4064)
			(end 0.7874 -0.4064)
			(stroke
				(width 0.1524)
				(type default)
			)
			(layer "F.SilkS")
		)
		(fp_poly
			(pts
				(xy -0.5334 0.254) (xy -0.635 0.254) (xy -0.635 0.2286) (xy -0.635 -0.254) (xy -0.5334 -0.254) (xy -0.5334 -0.2794)
				(xy 0.5334 -0.2794) (xy 0.5334 -0.254) (xy 0.635 -0.254) (xy 0.635 0.254) (xy 0.5334 0.254) (xy 0.5334 0.2794)
				(xy -0.508 0.2794) (xy -0.5334 0.2794)
			)
			(stroke
				(width 0)
				(type default)
			)
			(fill no)
			(layer "F.CrtYd")
		)
		(pad "1" smd rect
			(at 0.40005 0 180)
			(size 0.4572 0.508)
			(layers "F.Cu" "F.Mask" "F.Paste")
			(net "P3V3_NODE1")
		)
		(pad "2" smd rect
			(at -0.40005 0 180)
			(size 0.4572 0.508)
			(layers "F.Cu" "F.Mask" "F.Paste")
			(net "GND")
		)
	)
	(footprint ""
		(layer "F.Cu")
		(at 96.719644 -131.158488 90)
		(property "Reference" "C809"
			(at 0.149352 1.641602 90)
			(unlocked yes)
			(layer "F.SilkS")
			(effects
				(font
					(size 0.7874 0.5842)
					(thickness 0.1524)
				)
				(justify left)
			)
		)
		(property "Value" ""
			(at 0 0 90)
			(layer "F.Fab")
			(effects
				(font
					(size 1.27 1.27)
				)
			)
		)
		(duplicate_pad_numbers_are_jumpers no)
		(fp_line
			(start 0.7874 -0.4064)
			(end 0.7874 0.4064)
			(stroke
				(width 0.1524)
				(type default)
			)
			(layer "F.SilkS")
		)
		(fp_line
			(start -0.7874 -0.4064)
			(end 0.7874 -0.4064)
			(stroke
				(width 0.1524)
				(type default)
			)
			(layer "F.SilkS")
		)
		(fp_line
			(start 0 0.381)
			(end 0 -0.381)
			(stroke
				(width 0.1524)
				(type default)
			)
			(layer "F.SilkS")
		)
		(fp_line
			(start 0.7874 0.4064)
			(end -0.7874 0.4064)
			(stroke
				(width 0.1524)
				(type default)
			)
			(layer "F.SilkS")
		)
		(fp_line
			(start -0.7874 0.4064)
			(end -0.7874 -0.4064)
			(stroke
				(width 0.1524)
				(type default)
			)
			(layer "F.SilkS")
		)
		(fp_poly
			(pts
				(xy -0.5334 0.254) (xy -0.635 0.254) (xy -0.635 0.2286) (xy -0.635 -0.254) (xy -0.5334 -0.254) (xy -0.5334 -0.2794)
				(xy 0.5334 -0.2794) (xy 0.5334 -0.254) (xy 0.635 -0.254) (xy 0.635 0.254) (xy 0.5334 0.254) (xy 0.5334 0.2794)
				(xy -0.508 0.2794) (xy -0.5334 0.2794)
			)
			(stroke
				(width 0)
				(type default)
			)
			(fill no)
			(layer "F.CrtYd")
		)
		(pad "1" smd rect
			(at 0.40005 0 90)
			(size 0.4572 0.508)
			(layers "F.Cu" "F.Mask" "F.Paste")
			(net "P5V_STB_NODE1")
		)
		(pad "2" smd rect
			(at -0.40005 0 90)
			(size 0.4572 0.508)
			(layers "F.Cu" "F.Mask" "F.Paste")
			(net "GND")
		)
	)
	(footprint ""
		(layer "F.Cu")
		(at 148.193252 -137.31875 180)
		(property "Reference" "R1229"
			(at -0.949706 0.089154 0)
			(unlocked yes)
			(layer "F.SilkS")
			(effects
				(font
					(size 0.635 0.4064)
					(thickness 0.1524)
				)
				(justify left)
			)
		)
		(property "Value" ""
			(at 0 0 180)
			(layer "F.Fab")
			(effects
				(font
					(size 1.27 1.27)
				)
			)
		)
		(duplicate_pad_numbers_are_jumpers no)
		(fp_line
			(start 0.7874 0.4064)
			(end -0.7874 0.4064)
			(stroke
				(width 0.1524)
				(type default)
			)
			(layer "F.SilkS")
		)
		(fp_line
			(start 0.7874 -0.4064)
			(end 0.7874 0.4064)
			(stroke
				(width 0.1524)
				(type default)
			)
			(layer "F.SilkS")
		)
		(fp_line
			(start -0.7874 0.4064)
			(end -0.7874 -0.4064)
			(stroke
				(width 0.1524)
				(type default)
			)
			(layer "F.SilkS")
		)
		(fp_line
			(start -0.7874 -0.4064)
			(end 0.7874 -0.4064)
			(stroke
				(width 0.1524)
				(type default)
			)
			(layer "F.SilkS")
		)
		(fp_poly
			(pts
				(xy -0.508 0.2794) (xy -0.508 0.2286) (xy -0.635 0.2286) (xy -0.635 -0.254) (xy -0.5334 -0.254)
				(xy -0.5334 -0.2794) (xy 0.5334 -0.2794) (xy 0.5334 -0.254) (xy 0.635 -0.254) (xy 0.635 0.254) (xy 0.5334 0.254)
				(xy 0.5334 0.2794)
			)
			(stroke
				(width 0)
				(type default)
			)
			(fill no)
			(layer "F.CrtYd")
		)
		(pad "1" smd rect
			(at 0.40005 0 180)
			(size 0.4572 0.508)
			(layers "F.Cu" "F.Mask" "F.Paste")
			(net "PCIE_SW_PRSNT2")
		)
		(pad "2" smd rect
			(at -0.40005 0 180)
			(size 0.4572 0.508)
			(layers "F.Cu" "F.Mask" "F.Paste")
			(net "GND")
		)
	)
	(footprint ""
		(layer "F.Cu")
		(at 51.03114 -166.43985 90)
		(property "Reference" "R561"
			(at -130.36804 -3.432048 90)
			(unlocked yes)
			(layer "F.SilkS")
			(effects
				(font
					(size 0.7874 0.5842)
					(thickness 0.1524)
				)
				(justify left)
			)
		)
		(property "Value" ""
			(at 0 0 90)
			(layer "F.Fab")
			(effects
				(font
					(size 1.27 1.27)
				)
			)
		)
		(duplicate_pad_numbers_are_jumpers no)
		(fp_line
			(start 0.7874 -0.4064)
			(end 0.7874 0.4064)
			(stroke
				(width 0.1524)
				(type default)
			)
			(layer "F.SilkS")
		)
		(fp_line
			(start -0.7874 -0.4064)
			(end 0.7874 -0.4064)
			(stroke
				(width 0.1524)
				(type default)
			)
			(layer "F.SilkS")
		)
		(fp_line
			(start 0.7874 0.4064)
			(end -0.7874 0.4064)
			(stroke
				(width 0.1524)
				(type default)
			)
			(layer "F.SilkS")
		)
		(fp_line
			(start -0.7874 0.4064)
			(end -0.7874 -0.4064)
			(stroke
				(width 0.1524)
				(type default)
			)
			(layer "F.SilkS")
		)
		(fp_poly
			(pts
				(xy -0.508 0.2794) (xy -0.508 0.2286) (xy -0.635 0.2286) (xy -0.635 -0.254) (xy -0.5334 -0.254)
				(xy -0.5334 -0.2794) (xy 0.5334 -0.2794) (xy 0.5334 -0.254) (xy 0.635 -0.254) (xy 0.635 0.254) (xy 0.5334 0.254)
				(xy 0.5334 0.2794)
			)
			(stroke
				(width 0)
				(type default)
			)
			(fill no)
			(layer "F.CrtYd")
		)
		(pad "1" smd rect
			(at 0.40005 0 90)
			(size 0.4572 0.508)
			(layers "F.Cu" "F.Mask" "F.Paste")
			(net "PCH_I2C_ALERT_N")
		)
		(pad "2" smd rect
			(at -0.40005 0 90)
			(size 0.4572 0.508)
			(layers "F.Cu" "F.Mask" "F.Paste")
			(net "SMB_LAN1_ALT_N")
		)
	)
)
